# S9S_MB_2U (Grand Teton) — schematic netlist excerpt (pin names and nets, part order shuffled) for the footprints in the layout excerpt that follows; sources: Cadence DE-HDL packaged netlist, KiCad conversion of 03242023_DA0F0TMBIJ0_F0T_Motherboard_J_brd_V01_OCP.brd

R1388  Q_RES  2K 1% EMPTY  pkg 0402LF  page 219 : A = PWRGD_DRAMPWRGD_CPU1_EF_R_LVC1 ; B = GND
R920  Q_RES  1K 1% EMPTY  pkg 0402LF  page 221 : A = JTAG_PLD_JTAGEN ; B = GND

(kicad_pcb
	(version 20260206)
	(generator "pcbnew")
	(generator_version "10.0")
	(general
		(thickness 1.6)
		(legacy_teardrops no)
	)
	(paper "A4")
	(title_block
		(title "03242023_DA0F0TMBIJ0_F0T_Motherboard_J_brd_V01_OCP.brd")
		(comment 1 "Grand Teton / footprints 4269-4270 of 6105")
	)
	(layers
		(0 "F.Cu" signal "TOP")
		(4 "In1.Cu" signal "GND")
		(6 "In2.Cu" signal "IN1")
		(8 "In3.Cu" signal "GND1")
		(10 "In4.Cu" signal "IN2")
		(12 "In5.Cu" signal "GND2")
		(14 "In6.Cu" signal "IN3")
		(16 "In7.Cu" signal "GND3")
		(18 "In8.Cu" signal "VCC")
		(20 "In9.Cu" signal "VCC1")
		(22 "In10.Cu" signal "GND4")
		(24 "In11.Cu" signal "IN4")
		(26 "In12.Cu" signal "GND5")
		(28 "In13.Cu" signal "IN5")
		(30 "In14.Cu" signal "GND6")
		(32 "In15.Cu" signal "IN6")
		(34 "In16.Cu" signal "GND7")
		(2 "B.Cu" signal "BOTTOM")
		(9 "F.Adhes" user "F.Adhesive")
		(11 "B.Adhes" user "B.Adhesive")
		(13 "F.Paste" user "Package Geometry/Pastemask Top")
		(15 "B.Paste" user "Package Geometry/Pastemask Bottom")
		(5 "F.SilkS" user "Ref Des/Silkscreen Top")
		(7 "B.SilkS" user "Ref Des/Silkscreen Bottom")
		(1 "F.Mask" user "Board Geometry/Soldermask Top")
		(3 "B.Mask" user "Board Geometry/Soldermask Bottom")
		(17 "Dwgs.User" user "User.Drawings")
		(19 "Cmts.User" user "User.Comments")
		(21 "Eco1.User" user "User.Eco1")
		(23 "Eco2.User" user "User.Eco2")
		(25 "Edge.Cuts" user "Board Geometry/Outline")
		(27 "Margin" user)
		(31 "F.CrtYd" user "Package Geometry/Place Bound Top")
		(29 "B.CrtYd" user "Package Geometry/Place Bound Bottom")
		(35 "F.Fab" user "Ref Des/Assembly Top")
		(33 "B.Fab" user "Ref Des/Assembly Bottom")
	)
	(footprint ""
		(layer "B.Cu")
		(at 197.437502 -109.89691 180)
		(property "Reference" "R1388"
			(at 0 0 0)
			(layer "B.SilkS")
			(hide yes)
			(effects
				(font
					(size 1.27 1.27)
				)
				(justify mirror)
			)
		)
		(property "Value" ""
			(at 0 0 0)
			(layer "B.Fab")
			(effects
				(font
					(size 1.27 1.27)
				)
				(justify mirror)
			)
		)
		(duplicate_pad_numbers_are_jumpers no)
		(fp_line
			(start 0.7874 0.4064)
			(end 0.7874 -0.4064)
			(stroke
				(width 0.1524)
				(type default)
			)
			(layer "B.SilkS")
		)
		(fp_line
			(start 0.7874 -0.4064)
			(end -0.7874 -0.4064)
			(stroke
				(width 0.1524)
				(type default)
			)
			(layer "B.SilkS")
		)
		(fp_line
			(start -0.7874 0.4064)
			(end 0.7874 0.4064)
			(stroke
				(width 0.1524)
				(type default)
			)
			(layer "B.SilkS")
		)
		(fp_line
			(start -0.7874 -0.4064)
			(end -0.7874 0.4064)
			(stroke
				(width 0.1524)
				(type default)
			)
			(layer "B.SilkS")
		)
		(fp_line
			(start 0.67945 0.3048)
			(end 0.67945 -0.305054)
			(stroke
				(width 0.1)
				(type default)
			)
			(layer "B.Fab")
		)
		(fp_line
			(start 0.67945 -0.305054)
			(end 0.12065 -0.305054)
			(stroke
				(width 0.1)
				(type default)
			)
			(layer "B.Fab")
		)
		(fp_line
			(start 0.12065 0.3048)
			(end 0.67945 0.3048)
			(stroke
				(width 0.1)
				(type default)
			)
			(layer "B.Fab")
		)
		(fp_line
			(start 0.12065 0.2794)
			(end 0.12065 0.3048)
			(stroke
				(width 0.1)
				(type default)
			)
			(layer "B.Fab")
		)
		(fp_line
			(start 0.12065 -0.2794)
			(end -0.12065 -0.2794)
			(stroke
				(width 0.1)
				(type default)
			)
			(layer "B.Fab")
		)
		(fp_line
			(start 0.12065 -0.305054)
			(end 0.12065 -0.2794)
			(stroke
				(width 0.1)
				(type default)
			)
			(layer "B.Fab")
		)
		(fp_line
			(start -0.120396 0.3048)
			(end -0.120396 0.2794)
			(stroke
				(width 0.1)
				(type default)
			)
			(layer "B.Fab")
		)
		(fp_line
			(start -0.120396 0.2794)
			(end 0.12065 0.2794)
			(stroke
				(width 0.1)
				(type default)
			)
			(layer "B.Fab")
		)
		(fp_line
			(start -0.12065 -0.2794)
			(end -0.12065 -0.3048)
			(stroke
				(width 0.1)
				(type default)
			)
			(layer "B.Fab")
		)
		(fp_line
			(start -0.12065 -0.3048)
			(end -0.67945 -0.3048)
			(stroke
				(width 0.1)
				(type default)
			)
			(layer "B.Fab")
		)
		(fp_line
			(start -0.67945 0.3048)
			(end -0.120396 0.3048)
			(stroke
				(width 0.1)
				(type default)
			)
			(layer "B.Fab")
		)
		(fp_line
			(start -0.67945 -0.3048)
			(end -0.67945 0.3048)
			(stroke
				(width 0.1)
				(type default)
			)
			(layer "B.Fab")
		)
		(pad "1" smd circle
			(at 0.40005 0)
			(size 0 0)
			(layers "B.Cu" "B.Mask" "B.Paste")
			(net "PWRGD_DRAMPWRGD_CPU1_EF_R_LVC1")
		)
		(pad "2" smd circle
			(at -0.40005 0)
			(size 0 0)
			(layers "B.Cu" "B.Mask" "B.Paste")
			(net "GND")
		)
	)
	(footprint ""
		(layer "B.Cu")
		(at 160.83788 -117.566948)
		(property "Reference" "R920"
			(at 0 0 0)
			(layer "B.SilkS")
			(hide yes)
			(effects
				(font
					(size 1.27 1.27)
				)
				(justify mirror)
			)
		)
		(property "Value" ""
			(at 0 0 0)
			(layer "B.Fab")
			(effects
				(font
					(size 1.27 1.27)
				)
				(justify mirror)
			)
		)
		(duplicate_pad_numbers_are_jumpers no)
		(fp_line
			(start -0.7874 -0.4064)
			(end -0.7874 0.4064)
			(stroke
				(width 0.1524)
				(type default)
			)
			(layer "B.SilkS")
		)
		(fp_line
			(start -0.7874 0.4064)
			(end 0.7874 0.4064)
			(stroke
				(width 0.1524)
				(type default)
			)
			(layer "B.SilkS")
		)
		(fp_line
			(start 0.7874 -0.4064)
			(end -0.7874 -0.4064)
			(stroke
				(width 0.1524)
				(type default)
			)
			(layer "B.SilkS")
		)
		(fp_line
			(start 0.7874 0.4064)
			(end 0.7874 -0.4064)
			(stroke
				(width 0.1524)
				(type default)
			)
			(layer "B.SilkS")
		)
		(fp_line
			(start -0.67945 -0.3048)
			(end -0.67945 0.3048)
			(stroke
				(width 0.1)
				(type default)
			)
			(layer "B.Fab")
		)
		(fp_line
			(start -0.67945 0.3048)
			(end -0.120396 0.3048)
			(stroke
				(width 0.1)
				(type default)
			)
			(layer "B.Fab")
		)
		(fp_line
			(start -0.12065 -0.3048)
			(end -0.67945 -0.3048)
			(stroke
				(width 0.1)
				(type default)
			)
			(layer "B.Fab")
		)
		(fp_line
			(start -0.12065 -0.2794)
			(end -0.12065 -0.3048)
			(stroke
				(width 0.1)
				(type default)
			)
			(layer "B.Fab")
		)
		(fp_line
			(start -0.120396 0.2794)
			(end 0.12065 0.2794)
			(stroke
				(width 0.1)
				(type default)
			)
			(layer "B.Fab")
		)
		(fp_line
			(start -0.120396 0.3048)
			(end -0.120396 0.2794)
			(stroke
				(width 0.1)
				(type default)
			)
			(layer "B.Fab")
		)
		(fp_line
			(start 0.12065 -0.305054)
			(end 0.12065 -0.2794)
			(stroke
				(width 0.1)
				(type default)
			)
			(layer "B.Fab")
		)
		(fp_line
			(start 0.12065 -0.2794)
			(end -0.12065 -0.2794)
			(stroke
				(width 0.1)
				(type default)
			)
			(layer "B.Fab")
		)
		(fp_line
			(start 0.12065 0.2794)
			(end 0.12065 0.3048)
			(stroke
				(width 0.1)
				(type default)
			)
			(layer "B.Fab")
		)
		(fp_line
			(start 0.12065 0.3048)
			(end 0.67945 0.3048)
			(stroke
				(width 0.1)
				(type default)
			)
			(layer "B.Fab")
		)
		(fp_line
			(start 0.67945 -0.305054)
			(end 0.12065 -0.305054)
			(stroke
				(width 0.1)
				(type default)
			)
			(layer "B.Fab")
		)
		(fp_line
			(start 0.67945 0.3048)
			(end 0.67945 -0.305054)
			(stroke
				(width 0.1)
				(type default)
			)
			(layer "B.Fab")
		)
		(pad "1" smd circle
			(at 0.40005 0 180)
			(size 0 0)
			(layers "B.Cu" "B.Mask" "B.Paste")
			(net "JTAG_PLD_JTAGEN")
		)
		(pad "2" smd circle
			(at -0.40005 0 180)
			(size 0 0)
			(layers "B.Cu" "B.Mask" "B.Paste")
			(net "GND")
		)
	)
)
